(kicad_pcb
	(version 20260206)
	(generator "pcbnew")
	(generator_version "10.0")
	(general
		(thickness 1.6)
		(legacy_teardrops no)
	)
	(paper "A4")
	(title_block
		(title "9054_F0T_PDB_BD_GPU_F_V04_1213_1550_OCP.brd")
		(comment 1 "Grand Teton / footprints 410-417 of 608")
	)
	(layers
		(0 "F.Cu" signal "TOP")
		(4 "In1.Cu" signal "GND")
		(6 "In2.Cu" signal "IN1")
		(8 "In3.Cu" signal "GND1")
		(10 "In4.Cu" signal "VCC")
		(12 "In5.Cu" signal "VCC1")
		(14 "In6.Cu" signal "GND2")
		(16 "In7.Cu" signal "IN2")
		(18 "In8.Cu" signal "GND3")
		(2 "B.Cu" signal "BOTTOM")
		(9 "F.Adhes" user "F.Adhesive")
		(11 "B.Adhes" user "B.Adhesive")
		(13 "F.Paste" user "Package Geometry/Pastemask Top")
		(15 "B.Paste" user "Package Geometry/Pastemask Bottom")
		(5 "F.SilkS" user "Ref Des/Silkscreen Top")
		(7 "B.SilkS" user "Ref Des/Silkscreen Bottom")
		(1 "F.Mask" user "Board Geometry/Soldermask Top")
		(3 "B.Mask" user "Board Geometry/Soldermask Bottom")
		(17 "Dwgs.User" user "User.Drawings")
		(19 "Cmts.User" user "User.Comments")
		(21 "Eco1.User" user "User.Eco1")
		(23 "Eco2.User" user "User.Eco2")
		(25 "Edge.Cuts" user "Board Geometry/Outline")
		(27 "Margin" user)
		(31 "F.CrtYd" user "Package Geometry/Place Bound Top")
		(29 "B.CrtYd" user "Package Geometry/Place Bound Bottom")
		(35 "F.Fab" user "Ref Des/Assembly Top")
		(33 "B.Fab" user "Ref Des/Assembly Bottom")
	)
	(footprint ""
		(layer "B.Cu")
		(at 154.351736 -63.754 90)
		(property "Reference" "PC601"
			(at 0 0 90)
			(layer "B.SilkS")
			(hide yes)
			(effects
				(font
					(size 1.27 1.27)
				)
				(justify mirror)
			)
		)
		(property "Value" ""
			(at 0 0 90)
			(layer "B.Fab")
			(effects
				(font
					(size 1.27 1.27)
				)
				(justify mirror)
			)
		)
		(duplicate_pad_numbers_are_jumpers no)
		(fp_line
			(start 0.7874 -0.4064)
			(end -0.7874 -0.4064)
			(stroke
				(width 0.1524)
				(type default)
			)
			(layer "B.SilkS")
		)
		(fp_line
			(start -0.7874 -0.4064)
			(end -0.7874 0.4064)
			(stroke
				(width 0.1524)
				(type default)
			)
			(layer "B.SilkS")
		)
		(fp_line
			(start 0.7874 0.4064)
			(end 0.7874 -0.4064)
			(stroke
				(width 0.1524)
				(type default)
			)
			(layer "B.SilkS")
		)
		(fp_line
			(start -0.7874 0.4064)
			(end 0.7874 0.4064)
			(stroke
				(width 0.1524)
				(type default)
			)
			(layer "B.SilkS")
		)
		(fp_line
			(start 0.67945 -0.305054)
			(end 0.12065 -0.305054)
			(stroke
				(width 0.1)
				(type default)
			)
			(layer "B.Fab")
		)
		(fp_line
			(start 0.12065 -0.305054)
			(end 0.12065 -0.2794)
			(stroke
				(width 0.1)
				(type default)
			)
			(layer "B.Fab")
		)
		(fp_line
			(start -0.12065 -0.3048)
			(end -0.67945 -0.3048)
			(stroke
				(width 0.1)
				(type default)
			)
			(layer "B.Fab")
		)
		(fp_line
			(start -0.67945 -0.3048)
			(end -0.67945 0.3048)
			(stroke
				(width 0.1)
				(type default)
			)
			(layer "B.Fab")
		)
		(fp_line
			(start 0.12065 -0.2794)
			(end -0.12065 -0.2794)
			(stroke
				(width 0.1)
				(type default)
			)
			(layer "B.Fab")
		)
		(fp_line
			(start -0.12065 -0.2794)
			(end -0.12065 -0.3048)
			(stroke
				(width 0.1)
				(type default)
			)
			(layer "B.Fab")
		)
		(fp_line
			(start 0.12065 0.2794)
			(end 0.12065 0.3048)
			(stroke
				(width 0.1)
				(type default)
			)
			(layer "B.Fab")
		)
		(fp_line
			(start -0.120396 0.2794)
			(end 0.12065 0.2794)
			(stroke
				(width 0.1)
				(type default)
			)
			(layer "B.Fab")
		)
		(fp_line
			(start 0.67945 0.3048)
			(end 0.67945 -0.305054)
			(stroke
				(width 0.1)
				(type default)
			)
			(layer "B.Fab")
		)
		(fp_line
			(start 0.12065 0.3048)
			(end 0.67945 0.3048)
			(stroke
				(width 0.1)
				(type default)
			)
			(layer "B.Fab")
		)
		(fp_line
			(start -0.120396 0.3048)
			(end -0.120396 0.2794)
			(stroke
				(width 0.1)
				(type default)
			)
			(layer "B.Fab")
		)
		(fp_line
			(start -0.67945 0.3048)
			(end -0.120396 0.3048)
			(stroke
				(width 0.1)
				(type default)
			)
			(layer "B.Fab")
		)
		(pad "1" smd circle
			(at 0.40005 0 270)
			(size 0 0)
			(layers "B.Cu" "B.Mask" "B.Paste")
			(net "P52V_HS2_TEMP")
		)
		(pad "2" smd circle
			(at -0.40005 0 270)
			(size 0 0)
			(layers "B.Cu" "B.Mask" "B.Paste")
			(net "GND1_FIELD_SIGNAL")
		)
	)
	(footprint ""
		(layer "B.Cu")
		(at 169.210736 -72.263 180)
		(property "Reference" "R5884"
			(at 0 0 0)
			(layer "B.SilkS")
			(hide yes)
			(effects
				(font
					(size 1.27 1.27)
				)
				(justify mirror)
			)
		)
		(property "Value" ""
			(at 0 0 0)
			(layer "B.Fab")
			(effects
				(font
					(size 1.27 1.27)
				)
				(justify mirror)
			)
		)
		(duplicate_pad_numbers_are_jumpers no)
		(fp_line
			(start 0.7874 0.4064)
			(end 0.7874 -0.4064)
			(stroke
				(width 0.1524)
				(type default)
			)
			(layer "B.SilkS")
		)
		(fp_line
			(start 0.7874 -0.4064)
			(end -0.7874 -0.4064)
			(stroke
				(width 0.1524)
				(type default)
			)
			(layer "B.SilkS")
		)
		(fp_line
			(start -0.7874 0.4064)
			(end 0.7874 0.4064)
			(stroke
				(width 0.1524)
				(type default)
			)
			(layer "B.SilkS")
		)
		(fp_line
			(start -0.7874 -0.4064)
			(end -0.7874 0.4064)
			(stroke
				(width 0.1524)
				(type default)
			)
			(layer "B.SilkS")
		)
		(fp_line
			(start 0.67945 0.3048)
			(end 0.67945 -0.305054)
			(stroke
				(width 0.1)
				(type default)
			)
			(layer "B.Fab")
		)
		(fp_line
			(start 0.67945 -0.305054)
			(end 0.12065 -0.305054)
			(stroke
				(width 0.1)
				(type default)
			)
			(layer "B.Fab")
		)
		(fp_line
			(start 0.12065 0.3048)
			(end 0.67945 0.3048)
			(stroke
				(width 0.1)
				(type default)
			)
			(layer "B.Fab")
		)
		(fp_line
			(start 0.12065 0.2794)
			(end 0.12065 0.3048)
			(stroke
				(width 0.1)
				(type default)
			)
			(layer "B.Fab")
		)
		(fp_line
			(start 0.12065 -0.2794)
			(end -0.12065 -0.2794)
			(stroke
				(width 0.1)
				(type default)
			)
			(layer "B.Fab")
		)
		(fp_line
			(start 0.12065 -0.305054)
			(end 0.12065 -0.2794)
			(stroke
				(width 0.1)
				(type default)
			)
			(layer "B.Fab")
		)
		(fp_line
			(start -0.120396 0.3048)
			(end -0.120396 0.2794)
			(stroke
				(width 0.1)
				(type default)
			)
			(layer "B.Fab")
		)
		(fp_line
			(start -0.120396 0.2794)
			(end 0.12065 0.2794)
			(stroke
				(width 0.1)
				(type default)
			)
			(layer "B.Fab")
		)
		(fp_line
			(start -0.12065 -0.2794)
			(end -0.12065 -0.3048)
			(stroke
				(width 0.1)
				(type default)
			)
			(layer "B.Fab")
		)
		(fp_line
			(start -0.12065 -0.3048)
			(end -0.67945 -0.3048)
			(stroke
				(width 0.1)
				(type default)
			)
			(layer "B.Fab")
		)
		(fp_line
			(start -0.67945 0.3048)
			(end -0.120396 0.3048)
			(stroke
				(width 0.1)
				(type default)
			)
			(layer "B.Fab")
		)
		(fp_line
			(start -0.67945 -0.3048)
			(end -0.67945 0.3048)
			(stroke
				(width 0.1)
				(type default)
			)
			(layer "B.Fab")
		)
		(pad "1" smd circle
			(at 0.40005 0)
			(size 0 0)
			(layers "B.Cu" "B.Mask" "B.Paste")
			(net "P3V3_AUX")
		)
		(pad "2" smd circle
			(at -0.40005 0)
			(size 0 0)
			(layers "B.Cu" "B.Mask" "B.Paste")
			(net "SMB_P52V_PDB_SCL_R2")
		)
	)
	(footprint ""
		(layer "B.Cu")
		(at 175.306736 -80.391 90)
		(property "Reference" "R5880"
			(at 0 0 90)
			(layer "B.SilkS")
			(hide yes)
			(effects
				(font
					(size 1.27 1.27)
				)
				(justify mirror)
			)
		)
		(property "Value" ""
			(at 0 0 90)
			(layer "B.Fab")
			(effects
				(font
					(size 1.27 1.27)
				)
				(justify mirror)
			)
		)
		(duplicate_pad_numbers_are_jumpers no)
		(fp_line
			(start 1.651 -0.8382)
			(end -1.651 -0.8382)
			(stroke
				(width 0.1524)
				(type default)
			)
			(layer "B.SilkS")
		)
		(fp_line
			(start -1.651 -0.8382)
			(end -1.651 0.8382)
			(stroke
				(width 0.1524)
				(type default)
			)
			(layer "B.SilkS")
		)
		(fp_line
			(start 1.651 0.8382)
			(end 1.651 -0.8382)
			(stroke
				(width 0.1524)
				(type default)
			)
			(layer "B.SilkS")
		)
		(fp_line
			(start -1.651 0.8382)
			(end 1.651 0.8382)
			(stroke
				(width 0.1524)
				(type default)
			)
			(layer "B.SilkS")
		)
		(fp_line
			(start 1.559814 -0.7366)
			(end 1.559814 0.7366)
			(stroke
				(width 0.1)
				(type default)
			)
			(layer "B.Fab")
		)
		(fp_line
			(start 1.524 -0.7366)
			(end 1.559814 -0.7366)
			(stroke
				(width 0.1)
				(type default)
			)
			(layer "B.Fab")
		)
		(fp_line
			(start -1.524 -0.7366)
			(end 1.524 -0.7366)
			(stroke
				(width 0.1)
				(type default)
			)
			(layer "B.Fab")
		)
		(fp_line
			(start -1.560576 -0.7366)
			(end -1.524 -0.7366)
			(stroke
				(width 0.1)
				(type default)
			)
			(layer "B.Fab")
		)
		(fp_line
			(start 1.559814 0.7366)
			(end 1.524 0.7366)
			(stroke
				(width 0.1)
				(type default)
			)
			(layer "B.Fab")
		)
		(fp_line
			(start 1.524 0.7366)
			(end -1.524 0.7366)
			(stroke
				(width 0.1)
				(type default)
			)
			(layer "B.Fab")
		)
		(fp_line
			(start -1.524 0.7366)
			(end -1.560576 0.7366)
			(stroke
				(width 0.1)
				(type default)
			)
			(layer "B.Fab")
		)
		(fp_line
			(start -1.560576 0.7366)
			(end -1.560576 -0.7366)
			(stroke
				(width 0.1)
				(type default)
			)
			(layer "B.Fab")
		)
		(pad "1" smd rect
			(at 0.94996 0 90)
			(size 1.1176 1.3716)
			(layers "B.Cu" "B.Mask" "B.Paste")
			(net "P52V_HS2")
		)
		(pad "2" smd rect
			(at -0.94996 0 90)
			(size 1.1176 1.3716)
			(layers "B.Cu" "B.Mask" "B.Paste")
			(net "PWRGD_P52V_HS2_PG")
		)
	)
	(footprint ""
		(layer "B.Cu")
		(at 263.2964 -77.978 90)
		(property "Reference" "PR5"
			(at 0 0 90)
			(layer "B.SilkS")
			(hide yes)
			(effects
				(font
					(size 1.27 1.27)
				)
				(justify mirror)
			)
		)
		(property "Value" ""
			(at 0 0 90)
			(layer "B.Fab")
			(effects
				(font
					(size 1.27 1.27)
				)
				(justify mirror)
			)
		)
		(duplicate_pad_numbers_are_jumpers no)
		(fp_line
			(start 2.234946 -0.9271)
			(end -2.234946 -0.9271)
			(stroke
				(width 0.1524)
				(type default)
			)
			(layer "B.SilkS")
		)
		(fp_line
			(start -2.234946 -0.9271)
			(end -2.234946 0.9271)
			(stroke
				(width 0.1524)
				(type default)
			)
			(layer "B.SilkS")
		)
		(fp_line
			(start 2.234946 0.9271)
			(end 2.234946 -0.9271)
			(stroke
				(width 0.1524)
				(type default)
			)
			(layer "B.SilkS")
		)
		(fp_line
			(start -2.234946 0.9271)
			(end 2.234946 0.9271)
			(stroke
				(width 0.1524)
				(type default)
			)
			(layer "B.SilkS")
		)
		(fp_line
			(start 1.575054 -0.824992)
			(end 1.575054 0.824992)
			(stroke
				(width 0.1)
				(type default)
			)
			(layer "B.Fab")
		)
		(fp_line
			(start -1.575054 -0.824992)
			(end 1.575054 -0.824992)
			(stroke
				(width 0.1)
				(type default)
			)
			(layer "B.Fab")
		)
		(fp_line
			(start 1.575054 0.824992)
			(end -1.575054 0.824992)
			(stroke
				(width 0.1)
				(type default)
			)
			(layer "B.Fab")
		)
		(fp_line
			(start -1.575054 0.824992)
			(end -1.575054 -0.824992)
			(stroke
				(width 0.1)
				(type default)
			)
			(layer "B.Fab")
		)
		(pad "1" smd rect
			(at 1.599946 0 270)
			(size 1.016 1.6002)
			(layers "B.Cu" "B.Mask" "B.Paste")
			(net "P52V_1")
		)
		(pad "2" smd rect
			(at -1.599946 0 270)
			(size 1.016 1.6002)
			(layers "B.Cu" "B.Mask" "B.Paste")
			(net "P52V_HS1_VCC")
		)
	)
	(footprint ""
		(layer "B.Cu")
		(at 187.8584 -40.259 90)
		(property "Reference" "FS6"
			(at -6.477 2.99593 270)
			(unlocked yes)
			(layer "B.SilkS")
			(effects
				(font
					(size 0.7874 0.5842)
					(thickness 0.1524)
				)
				(justify left mirror)
			)
		)
		(property "Value" ""
			(at 0 0 90)
			(layer "B.Fab")
			(effects
				(font
					(size 1.27 1.27)
				)
				(justify mirror)
			)
		)
		(duplicate_pad_numbers_are_jumpers no)
		(fp_line
			(start 6.427724 -1.8415)
			(end 6.427724 1.8415)
			(stroke
				(width 0.1524)
				(type default)
			)
			(layer "B.SilkS")
		)
		(fp_line
			(start -6.427724 -1.8415)
			(end 6.427724 -1.8415)
			(stroke
				(width 0.1524)
				(type default)
			)
			(layer "B.SilkS")
		)
		(fp_line
			(start 6.427724 1.8415)
			(end -6.427724 1.8415)
			(stroke
				(width 0.1524)
				(type default)
			)
			(layer "B.SilkS")
		)
		(fp_line
			(start -6.427724 1.8415)
			(end -6.427724 -1.8415)
			(stroke
				(width 0.1524)
				(type default)
			)
			(layer "B.SilkS")
		)
		(fp_line
			(start 5.225034 -1.610106)
			(end -5.225034 -1.610106)
			(stroke
				(width 0.1)
				(type default)
			)
			(layer "B.Fab")
		)
		(fp_line
			(start -5.225034 -1.610106)
			(end -5.225034 1.610106)
			(stroke
				(width 0.1)
				(type default)
			)
			(layer "B.Fab")
		)
		(fp_line
			(start 5.225034 1.610106)
			(end 5.225034 -1.610106)
			(stroke
				(width 0.1)
				(type default)
			)
			(layer "B.Fab")
		)
		(fp_line
			(start -5.225034 1.610106)
			(end 5.225034 1.610106)
			(stroke
				(width 0.1)
				(type default)
			)
			(layer "B.Fab")
		)
		(pad "1" smd rect
			(at 4.675124 0 270)
			(size 3.2512 3.429)
			(layers "B.Cu" "B.Mask" "B.Paste")
			(net "P52V_2_FUSE_1")
		)
		(pad "2" smd rect
			(at -4.675124 0 270)
			(size 3.2512 3.429)
			(layers "B.Cu" "B.Mask" "B.Paste")
			(net "P52V_2")
		)
	)
	(footprint ""
		(layer "B.Cu")
		(at 286.2834 -63.246 90)
		(property "Reference" "PR33"
			(at 0 0 90)
			(layer "B.SilkS")
			(hide yes)
			(effects
				(font
					(size 1.27 1.27)
				)
				(justify mirror)
			)
		)
		(property "Value" ""
			(at 0 0 90)
			(layer "B.Fab")
			(effects
				(font
					(size 1.27 1.27)
				)
				(justify mirror)
			)
		)
		(duplicate_pad_numbers_are_jumpers no)
		(fp_line
			(start 0.7874 -0.4064)
			(end -0.7874 -0.4064)
			(stroke
				(width 0.1524)
				(type default)
			)
			(layer "B.SilkS")
		)
		(fp_line
			(start -0.7874 -0.4064)
			(end -0.7874 0.4064)
			(stroke
				(width 0.1524)
				(type default)
			)
			(layer "B.SilkS")
		)
		(fp_line
			(start 0.7874 0.4064)
			(end 0.7874 -0.4064)
			(stroke
				(width 0.1524)
				(type default)
			)
			(layer "B.SilkS")
		)
		(fp_line
			(start -0.7874 0.4064)
			(end 0.7874 0.4064)
			(stroke
				(width 0.1524)
				(type default)
			)
			(layer "B.SilkS")
		)
		(fp_line
			(start 0.67945 -0.305054)
			(end 0.12065 -0.305054)
			(stroke
				(width 0.1)
				(type default)
			)
			(layer "B.Fab")
		)
		(fp_line
			(start 0.12065 -0.305054)
			(end 0.12065 -0.2794)
			(stroke
				(width 0.1)
				(type default)
			)
			(layer "B.Fab")
		)
		(fp_line
			(start -0.12065 -0.3048)
			(end -0.67945 -0.3048)
			(stroke
				(width 0.1)
				(type default)
			)
			(layer "B.Fab")
		)
		(fp_line
			(start -0.67945 -0.3048)
			(end -0.67945 0.3048)
			(stroke
				(width 0.1)
				(type default)
			)
			(layer "B.Fab")
		)
		(fp_line
			(start 0.12065 -0.2794)
			(end -0.12065 -0.2794)
			(stroke
				(width 0.1)
				(type default)
			)
			(layer "B.Fab")
		)
		(fp_line
			(start -0.12065 -0.2794)
			(end -0.12065 -0.3048)
			(stroke
				(width 0.1)
				(type default)
			)
			(layer "B.Fab")
		)
		(fp_line
			(start 0.12065 0.2794)
			(end 0.12065 0.3048)
			(stroke
				(width 0.1)
				(type default)
			)
			(layer "B.Fab")
		)
		(fp_line
			(start -0.120396 0.2794)
			(end 0.12065 0.2794)
			(stroke
				(width 0.1)
				(type default)
			)
			(layer "B.Fab")
		)
		(fp_line
			(start 0.67945 0.3048)
			(end 0.67945 -0.305054)
			(stroke
				(width 0.1)
				(type default)
			)
			(layer "B.Fab")
		)
		(fp_line
			(start 0.12065 0.3048)
			(end 0.67945 0.3048)
			(stroke
				(width 0.1)
				(type default)
			)
			(layer "B.Fab")
		)
		(fp_line
			(start -0.120396 0.3048)
			(end -0.120396 0.2794)
			(stroke
				(width 0.1)
				(type default)
			)
			(layer "B.Fab")
		)
		(fp_line
			(start -0.67945 0.3048)
			(end -0.120396 0.3048)
			(stroke
				(width 0.1)
				(type default)
			)
			(layer "B.Fab")
		)
		(pad "1" smd circle
			(at 0.40005 0 270)
			(size 0 0)
			(layers "B.Cu" "B.Mask" "B.Paste")
			(net "HS1_TMR1")
		)
		(pad "2" smd circle
			(at -0.40005 0 270)
			(size 0 0)
			(layers "B.Cu" "B.Mask" "B.Paste")
			(net "HS1_TMR2")
		)
	)
	(footprint ""
		(layer "B.Cu")
		(at 168.829736 -66.675)
		(property "Reference" "PR7026"
			(at 0 0 0)
			(layer "B.SilkS")
			(hide yes)
			(effects
				(font
					(size 1.27 1.27)
				)
				(justify mirror)
			)
		)
		(property "Value" ""
			(at 0 0 0)
			(layer "B.Fab")
			(effects
				(font
					(size 1.27 1.27)
				)
				(justify mirror)
			)
		)
		(duplicate_pad_numbers_are_jumpers no)
		(fp_line
			(start -0.7874 -0.4064)
			(end -0.7874 0.4064)
			(stroke
				(width 0.1524)
				(type default)
			)
			(layer "B.SilkS")
		)
		(fp_line
			(start -0.7874 0.4064)
			(end 0.7874 0.4064)
			(stroke
				(width 0.1524)
				(type default)
			)
			(layer "B.SilkS")
		)
		(fp_line
			(start 0.7874 -0.4064)
			(end -0.7874 -0.4064)
			(stroke
				(width 0.1524)
				(type default)
			)
			(layer "B.SilkS")
		)
		(fp_line
			(start 0.7874 0.4064)
			(end 0.7874 -0.4064)
			(stroke
				(width 0.1524)
				(type default)
			)
			(layer "B.SilkS")
		)
		(fp_line
			(start -0.67945 -0.3048)
			(end -0.67945 0.3048)
			(stroke
				(width 0.1)
				(type default)
			)
			(layer "B.Fab")
		)
		(fp_line
			(start -0.67945 0.3048)
			(end -0.120396 0.3048)
			(stroke
				(width 0.1)
				(type default)
			)
			(layer "B.Fab")
		)
		(fp_line
			(start -0.12065 -0.3048)
			(end -0.67945 -0.3048)
			(stroke
				(width 0.1)
				(type default)
			)
			(layer "B.Fab")
		)
		(fp_line
			(start -0.12065 -0.2794)
			(end -0.12065 -0.3048)
			(stroke
				(width 0.1)
				(type default)
			)
			(layer "B.Fab")
		)
		(fp_line
			(start -0.120396 0.2794)
			(end 0.12065 0.2794)
			(stroke
				(width 0.1)
				(type default)
			)
			(layer "B.Fab")
		)
		(fp_line
			(start -0.120396 0.3048)
			(end -0.120396 0.2794)
			(stroke
				(width 0.1)
				(type default)
			)
			(layer "B.Fab")
		)
		(fp_line
			(start 0.12065 -0.305054)
			(end 0.12065 -0.2794)
			(stroke
				(width 0.1)
				(type default)
			)
			(layer "B.Fab")
		)
		(fp_line
			(start 0.12065 -0.2794)
			(end -0.12065 -0.2794)
			(stroke
				(width 0.1)
				(type default)
			)
			(layer "B.Fab")
		)
		(fp_line
			(start 0.12065 0.2794)
			(end 0.12065 0.3048)
			(stroke
				(width 0.1)
				(type default)
			)
			(layer "B.Fab")
		)
		(fp_line
			(start 0.12065 0.3048)
			(end 0.67945 0.3048)
			(stroke
				(width 0.1)
				(type default)
			)
			(layer "B.Fab")
		)
		(fp_line
			(start 0.67945 -0.305054)
			(end 0.12065 -0.305054)
			(stroke
				(width 0.1)
				(type default)
			)
			(layer "B.Fab")
		)
		(fp_line
			(start 0.67945 0.3048)
			(end 0.67945 -0.305054)
			(stroke
				(width 0.1)
				(type default)
			)
			(layer "B.Fab")
		)
		(pad "1" smd circle
			(at 0.40005 0 180)
			(size 0 0)
			(layers "B.Cu" "B.Mask" "B.Paste")
			(net "P52V_HS2_ISET")
		)
		(pad "2" smd circle
			(at -0.40005 0 180)
			(size 0 0)
			(layers "B.Cu" "B.Mask" "B.Paste")
			(net "P52V_HS2_VCAP")
		)
	)
	(footprint ""
		(layer "B.Cu")
		(at 26.015188 -153.501344)
		(property "Reference" ""
			(at 0 0 0)
			(layer "B.SilkS")
			(hide yes)
			(effects
				(font
					(size 1.27 1.27)
				)
				(justify mirror)
			)
		)
		(property "Value" ""
			(at 0 0 0)
			(layer "B.Fab")
			(effects
				(font
					(size 1.27 1.27)
				)
				(justify mirror)
			)
		)
		(duplicate_pad_numbers_are_jumpers no)
		(pad "1" smd circle
			(at 0 0 180)
			(size 0.9906 0.9906)
			(layers "B.Cu" "B.Mask" "B.Paste")
			(net "Net_243")
		)
		(zone
			(layer "B.Cu")
			(hatch none 0.5)
			(connect_pads
				(clearance 0)
			)
			(min_thickness 0.25)
			(keepout
				(tracks not_allowed)
				(vias allowed)
				(pads allowed)
				(copperpour not_allowed)
				(footprints allowed)
			)
			(placement
				(enabled no)
				(sheetname "")
			)
			(fill
				(thermal_gap 0.5)
				(thermal_bridge_width 0.5)
				(island_removal_mode 0)
			)
			(polygon
				(pts
					(arc
						(start 27.640788 -153.501344)
						(mid 24.389588 -153.501344)
						(end 27.640788 -153.501344)
					)
				)
			)
		)
	)
)
